(kicad_pcb
	(version 20260206)
	(generator "pcbnew")
	(generator_version "10.0")
	(general
		(thickness 1.6)
		(legacy_teardrops no)
	)
	(paper "A4")
	(title_block
		(title "12092022_DA0F0TMDCD0_F0T_Management_Board_D_brd_V3_OCP.brd")
		(comment 1 "Grand Teton / footprints 857-861 of 1440")
	)
	(layers
		(0 "F.Cu" signal "TOP")
		(4 "In1.Cu" signal "GND")
		(6 "In2.Cu" signal "IN1")
		(8 "In3.Cu" signal "GND1")
		(10 "In4.Cu" signal "IN2")
		(12 "In5.Cu" signal "VCC")
		(14 "In6.Cu" signal "VCC1")
		(16 "In7.Cu" signal "IN3")
		(18 "In8.Cu" signal "GND2")
		(20 "In9.Cu" signal "IN4")
		(22 "In10.Cu" signal "GND3")
		(2 "B.Cu" signal "BOTTOM")
		(9 "F.Adhes" user "F.Adhesive")
		(11 "B.Adhes" user "B.Adhesive")
		(13 "F.Paste" user "Package Geometry/Pastemask Top")
		(15 "B.Paste" user "Package Geometry/Pastemask Bottom")
		(5 "F.SilkS" user "Ref Des/Silkscreen Top")
		(7 "B.SilkS" user "Ref Des/Silkscreen Bottom")
		(1 "F.Mask" user "Board Geometry/Soldermask Top")
		(3 "B.Mask" user "Board Geometry/Soldermask Bottom")
		(17 "Dwgs.User" user "User.Drawings")
		(19 "Cmts.User" user "User.Comments")
		(21 "Eco1.User" user "User.Eco1")
		(23 "Eco2.User" user "User.Eco2")
		(25 "Edge.Cuts" user "Board Geometry/Outline")
		(27 "Margin" user)
		(31 "F.CrtYd" user "Package Geometry/Place Bound Top")
		(29 "B.CrtYd" user "Package Geometry/Place Bound Bottom")
		(35 "F.Fab" user "Ref Des/Assembly Top")
		(33 "B.Fab" user "Ref Des/Assembly Bottom")
	)
	(footprint ""
		(layer "B.Cu")
		(at 17.399 -17.907 -90)
		(property "Reference" "R416"
			(at 0 0 90)
			(layer "B.SilkS")
			(hide yes)
			(effects
				(font
					(size 1.27 1.27)
				)
				(justify mirror)
			)
		)
		(property "Value" ""
			(at 0 0 90)
			(layer "B.Fab")
			(effects
				(font
					(size 1.27 1.27)
				)
				(justify mirror)
			)
		)
		(duplicate_pad_numbers_are_jumpers no)
		(fp_line
			(start -0.7874 0.4064)
			(end 0.7874 0.4064)
			(stroke
				(width 0.1524)
				(type default)
			)
			(layer "B.SilkS")
		)
		(fp_line
			(start 0.7874 0.4064)
			(end 0.7874 -0.4064)
			(stroke
				(width 0.1524)
				(type default)
			)
			(layer "B.SilkS")
		)
		(fp_line
			(start -0.7874 -0.4064)
			(end -0.7874 0.4064)
			(stroke
				(width 0.1524)
				(type default)
			)
			(layer "B.SilkS")
		)
		(fp_line
			(start 0.7874 -0.4064)
			(end -0.7874 -0.4064)
			(stroke
				(width 0.1524)
				(type default)
			)
			(layer "B.SilkS")
		)
		(fp_line
			(start -0.67945 0.3048)
			(end -0.120396 0.3048)
			(stroke
				(width 0.1)
				(type default)
			)
			(layer "B.Fab")
		)
		(fp_line
			(start -0.120396 0.3048)
			(end -0.120396 0.2794)
			(stroke
				(width 0.1)
				(type default)
			)
			(layer "B.Fab")
		)
		(fp_line
			(start 0.12065 0.3048)
			(end 0.67945 0.3048)
			(stroke
				(width 0.1)
				(type default)
			)
			(layer "B.Fab")
		)
		(fp_line
			(start 0.67945 0.3048)
			(end 0.67945 -0.305054)
			(stroke
				(width 0.1)
				(type default)
			)
			(layer "B.Fab")
		)
		(fp_line
			(start -0.120396 0.2794)
			(end 0.12065 0.2794)
			(stroke
				(width 0.1)
				(type default)
			)
			(layer "B.Fab")
		)
		(fp_line
			(start 0.12065 0.2794)
			(end 0.12065 0.3048)
			(stroke
				(width 0.1)
				(type default)
			)
			(layer "B.Fab")
		)
		(fp_line
			(start -0.12065 -0.2794)
			(end -0.12065 -0.3048)
			(stroke
				(width 0.1)
				(type default)
			)
			(layer "B.Fab")
		)
		(fp_line
			(start 0.12065 -0.2794)
			(end -0.12065 -0.2794)
			(stroke
				(width 0.1)
				(type default)
			)
			(layer "B.Fab")
		)
		(fp_line
			(start -0.67945 -0.3048)
			(end -0.67945 0.3048)
			(stroke
				(width 0.1)
				(type default)
			)
			(layer "B.Fab")
		)
		(fp_line
			(start -0.12065 -0.3048)
			(end -0.67945 -0.3048)
			(stroke
				(width 0.1)
				(type default)
			)
			(layer "B.Fab")
		)
		(fp_line
			(start 0.12065 -0.305054)
			(end 0.12065 -0.2794)
			(stroke
				(width 0.1)
				(type default)
			)
			(layer "B.Fab")
		)
		(fp_line
			(start 0.67945 -0.305054)
			(end 0.12065 -0.305054)
			(stroke
				(width 0.1)
				(type default)
			)
			(layer "B.Fab")
		)
		(pad "1" smd circle
			(at 0.40005 0 90)
			(size 0 0)
			(layers "B.Cu" "B.Mask" "B.Paste")
			(net "P3V3_AUX")
		)
		(pad "2" smd circle
			(at -0.40005 0 90)
			(size 0 0)
			(layers "B.Cu" "B.Mask" "B.Paste")
			(net "TMC75_A0")
		)
	)
	(footprint ""
		(layer "B.Cu")
		(at 64.1604 -32.4612 90)
		(property "Reference" "R570"
			(at 0 0 90)
			(layer "B.SilkS")
			(hide yes)
			(effects
				(font
					(size 1.27 1.27)
				)
				(justify mirror)
			)
		)
		(property "Value" ""
			(at 0 0 90)
			(layer "B.Fab")
			(effects
				(font
					(size 1.27 1.27)
				)
				(justify mirror)
			)
		)
		(duplicate_pad_numbers_are_jumpers no)
		(fp_line
			(start 0.7874 -0.4064)
			(end -0.7874 -0.4064)
			(stroke
				(width 0.1524)
				(type default)
			)
			(layer "B.SilkS")
		)
		(fp_line
			(start -0.7874 -0.4064)
			(end -0.7874 0.4064)
			(stroke
				(width 0.1524)
				(type default)
			)
			(layer "B.SilkS")
		)
		(fp_line
			(start 0.7874 0.4064)
			(end 0.7874 -0.4064)
			(stroke
				(width 0.1524)
				(type default)
			)
			(layer "B.SilkS")
		)
		(fp_line
			(start -0.7874 0.4064)
			(end 0.7874 0.4064)
			(stroke
				(width 0.1524)
				(type default)
			)
			(layer "B.SilkS")
		)
		(fp_line
			(start 0.67945 -0.305054)
			(end 0.12065 -0.305054)
			(stroke
				(width 0.1)
				(type default)
			)
			(layer "B.Fab")
		)
		(fp_line
			(start 0.12065 -0.305054)
			(end 0.12065 -0.2794)
			(stroke
				(width 0.1)
				(type default)
			)
			(layer "B.Fab")
		)
		(fp_line
			(start -0.12065 -0.3048)
			(end -0.67945 -0.3048)
			(stroke
				(width 0.1)
				(type default)
			)
			(layer "B.Fab")
		)
		(fp_line
			(start -0.67945 -0.3048)
			(end -0.67945 0.3048)
			(stroke
				(width 0.1)
				(type default)
			)
			(layer "B.Fab")
		)
		(fp_line
			(start 0.12065 -0.2794)
			(end -0.12065 -0.2794)
			(stroke
				(width 0.1)
				(type default)
			)
			(layer "B.Fab")
		)
		(fp_line
			(start -0.12065 -0.2794)
			(end -0.12065 -0.3048)
			(stroke
				(width 0.1)
				(type default)
			)
			(layer "B.Fab")
		)
		(fp_line
			(start 0.12065 0.2794)
			(end 0.12065 0.3048)
			(stroke
				(width 0.1)
				(type default)
			)
			(layer "B.Fab")
		)
		(fp_line
			(start -0.120396 0.2794)
			(end 0.12065 0.2794)
			(stroke
				(width 0.1)
				(type default)
			)
			(layer "B.Fab")
		)
		(fp_line
			(start 0.67945 0.3048)
			(end 0.67945 -0.305054)
			(stroke
				(width 0.1)
				(type default)
			)
			(layer "B.Fab")
		)
		(fp_line
			(start 0.12065 0.3048)
			(end 0.67945 0.3048)
			(stroke
				(width 0.1)
				(type default)
			)
			(layer "B.Fab")
		)
		(fp_line
			(start -0.120396 0.3048)
			(end -0.120396 0.2794)
			(stroke
				(width 0.1)
				(type default)
			)
			(layer "B.Fab")
		)
		(fp_line
			(start -0.67945 0.3048)
			(end -0.120396 0.3048)
			(stroke
				(width 0.1)
				(type default)
			)
			(layer "B.Fab")
		)
		(pad "1" smd circle
			(at 0.40005 0 270)
			(size 0 0)
			(layers "B.Cu" "B.Mask" "B.Paste")
			(net "SMB_BMC_MM7_R_SDA")
		)
		(pad "2" smd circle
			(at -0.40005 0 270)
			(size 0 0)
			(layers "B.Cu" "B.Mask" "B.Paste")
			(net "SMB_BMC_MM7_SDA")
		)
	)
	(footprint ""
		(layer "B.Cu")
		(at 32.639 -106.553 -90)
		(property "Reference" "R243"
			(at 0 0 90)
			(layer "B.SilkS")
			(hide yes)
			(effects
				(font
					(size 1.27 1.27)
				)
				(justify mirror)
			)
		)
		(property "Value" ""
			(at 0 0 90)
			(layer "B.Fab")
			(effects
				(font
					(size 1.27 1.27)
				)
				(justify mirror)
			)
		)
		(duplicate_pad_numbers_are_jumpers no)
		(fp_line
			(start -0.7874 0.4064)
			(end 0.7874 0.4064)
			(stroke
				(width 0.1524)
				(type default)
			)
			(layer "B.SilkS")
		)
		(fp_line
			(start 0.7874 0.4064)
			(end 0.7874 -0.4064)
			(stroke
				(width 0.1524)
				(type default)
			)
			(layer "B.SilkS")
		)
		(fp_line
			(start -0.7874 -0.4064)
			(end -0.7874 0.4064)
			(stroke
				(width 0.1524)
				(type default)
			)
			(layer "B.SilkS")
		)
		(fp_line
			(start 0.7874 -0.4064)
			(end -0.7874 -0.4064)
			(stroke
				(width 0.1524)
				(type default)
			)
			(layer "B.SilkS")
		)
		(fp_line
			(start -0.67945 0.3048)
			(end -0.120396 0.3048)
			(stroke
				(width 0.1)
				(type default)
			)
			(layer "B.Fab")
		)
		(fp_line
			(start -0.120396 0.3048)
			(end -0.120396 0.2794)
			(stroke
				(width 0.1)
				(type default)
			)
			(layer "B.Fab")
		)
		(fp_line
			(start 0.12065 0.3048)
			(end 0.67945 0.3048)
			(stroke
				(width 0.1)
				(type default)
			)
			(layer "B.Fab")
		)
		(fp_line
			(start 0.67945 0.3048)
			(end 0.67945 -0.305054)
			(stroke
				(width 0.1)
				(type default)
			)
			(layer "B.Fab")
		)
		(fp_line
			(start -0.120396 0.2794)
			(end 0.12065 0.2794)
			(stroke
				(width 0.1)
				(type default)
			)
			(layer "B.Fab")
		)
		(fp_line
			(start 0.12065 0.2794)
			(end 0.12065 0.3048)
			(stroke
				(width 0.1)
				(type default)
			)
			(layer "B.Fab")
		)
		(fp_line
			(start -0.12065 -0.2794)
			(end -0.12065 -0.3048)
			(stroke
				(width 0.1)
				(type default)
			)
			(layer "B.Fab")
		)
		(fp_line
			(start 0.12065 -0.2794)
			(end -0.12065 -0.2794)
			(stroke
				(width 0.1)
				(type default)
			)
			(layer "B.Fab")
		)
		(fp_line
			(start -0.67945 -0.3048)
			(end -0.67945 0.3048)
			(stroke
				(width 0.1)
				(type default)
			)
			(layer "B.Fab")
		)
		(fp_line
			(start -0.12065 -0.3048)
			(end -0.67945 -0.3048)
			(stroke
				(width 0.1)
				(type default)
			)
			(layer "B.Fab")
		)
		(fp_line
			(start 0.12065 -0.305054)
			(end 0.12065 -0.2794)
			(stroke
				(width 0.1)
				(type default)
			)
			(layer "B.Fab")
		)
		(fp_line
			(start 0.67945 -0.305054)
			(end 0.12065 -0.305054)
			(stroke
				(width 0.1)
				(type default)
			)
			(layer "B.Fab")
		)
		(pad "1" smd circle
			(at 0.40005 0 90)
			(size 0 0)
			(layers "B.Cu" "B.Mask" "B.Paste")
			(net "PWRGD_PSU_AC_PWROK")
		)
		(pad "2" smd circle
			(at -0.40005 0 90)
			(size 0 0)
			(layers "B.Cu" "B.Mask" "B.Paste")
			(net "PWRGD_PSU_AC_PWROK_R")
		)
	)
	(footprint ""
		(layer "B.Cu")
		(at 17.907 -24.003 -90)
		(property "Reference" "PC268"
			(at 0 0 90)
			(layer "B.SilkS")
			(hide yes)
			(effects
				(font
					(size 1.27 1.27)
				)
				(justify mirror)
			)
		)
		(property "Value" ""
			(at 0 0 90)
			(layer "B.Fab")
			(effects
				(font
					(size 1.27 1.27)
				)
				(justify mirror)
			)
		)
		(duplicate_pad_numbers_are_jumpers no)
		(fp_line
			(start -1.651 0.8382)
			(end 1.651 0.8382)
			(stroke
				(width 0.1524)
				(type default)
			)
			(layer "B.SilkS")
		)
		(fp_line
			(start 0 0.8382)
			(end 0 -0.8382)
			(stroke
				(width 0.1524)
				(type default)
			)
			(layer "B.SilkS")
		)
		(fp_line
			(start 1.651 0.8382)
			(end 1.651 -0.8382)
			(stroke
				(width 0.1524)
				(type default)
			)
			(layer "B.SilkS")
		)
		(fp_line
			(start -1.651 -0.8382)
			(end -1.651 0.8382)
			(stroke
				(width 0.1524)
				(type default)
			)
			(layer "B.SilkS")
		)
		(fp_line
			(start 1.651 -0.8382)
			(end -1.651 -0.8382)
			(stroke
				(width 0.1524)
				(type default)
			)
			(layer "B.SilkS")
		)
		(fp_line
			(start -1.55956 0.7366)
			(end -1.55956 -0.7366)
			(stroke
				(width 0.1)
				(type default)
			)
			(layer "B.Fab")
		)
		(fp_line
			(start -1.524 0.7366)
			(end -1.55956 0.7366)
			(stroke
				(width 0.1)
				(type default)
			)
			(layer "B.Fab")
		)
		(fp_line
			(start 1.524 0.7366)
			(end -1.524 0.7366)
			(stroke
				(width 0.1)
				(type default)
			)
			(layer "B.Fab")
		)
		(fp_line
			(start 1.55956 0.7366)
			(end 1.524 0.7366)
			(stroke
				(width 0.1)
				(type default)
			)
			(layer "B.Fab")
		)
		(fp_line
			(start -1.55956 -0.7366)
			(end -1.524 -0.7366)
			(stroke
				(width 0.1)
				(type default)
			)
			(layer "B.Fab")
		)
		(fp_line
			(start -1.524 -0.7366)
			(end 1.524 -0.7366)
			(stroke
				(width 0.1)
				(type default)
			)
			(layer "B.Fab")
		)
		(fp_line
			(start 1.524 -0.7366)
			(end 1.55956 -0.7366)
			(stroke
				(width 0.1)
				(type default)
			)
			(layer "B.Fab")
		)
		(fp_line
			(start 1.55956 -0.7366)
			(end 1.55956 0.7366)
			(stroke
				(width 0.1)
				(type default)
			)
			(layer "B.Fab")
		)
		(pad "1" smd rect
			(at 0.94996 0 270)
			(size 1.1176 1.3716)
			(layers "B.Cu" "B.Mask" "B.Paste")
			(net "P1V0_AUX")
		)
		(pad "2" smd rect
			(at -0.94996 0 270)
			(size 1.1176 1.3716)
			(layers "B.Cu" "B.Mask" "B.Paste")
			(net "GND")
		)
	)
	(footprint ""
		(layer "B.Cu")
		(at 95.926656 53.375814 90)
		(property "Reference" "J11"
			(at -0.980186 -2.862326 270)
			(unlocked yes)
			(layer "B.SilkS")
			(effects
				(font
					(size 0.7874 0.5842)
					(thickness 0.1524)
				)
				(justify left mirror)
			)
		)
		(property "Value" ""
			(at 0 0 90)
			(layer "B.Fab")
			(effects
				(font
					(size 1.27 1.27)
				)
				(justify mirror)
			)
		)
		(duplicate_pad_numbers_are_jumpers no)
		(fp_line
			(start 1.2192 -2.1082)
			(end -1.2192 -2.1082)
			(stroke
				(width 0.1524)
				(type default)
			)
			(layer "B.SilkS")
		)
		(fp_line
			(start -1.2192 -2.1082)
			(end -1.2192 -0.801624)
			(stroke
				(width 0.1524)
				(type default)
			)
			(layer "B.SilkS")
		)
		(fp_line
			(start -1.2192 0.866394)
			(end -1.2192 2.1082)
			(stroke
				(width 0.1524)
				(type default)
			)
			(layer "B.SilkS")
		)
		(fp_line
			(start 1.2192 2.1082)
			(end 1.2192 -2.1082)
			(stroke
				(width 0.1524)
				(type default)
			)
			(layer "B.SilkS")
		)
		(fp_line
			(start -1.2192 2.1082)
			(end 1.2192 2.1082)
			(stroke
				(width 0.1524)
				(type default)
			)
			(layer "B.SilkS")
		)
		(pad "" np_thru_hole circle
			(at -3.4671 -1.27)
			(size 1.0414 1.0414)
			(drill 1.0414)
			(layers "*.Cu" "*.Mask")
			(clearance 0.381)
			(thermal_gap 0.381)
		)
		(pad "" np_thru_hole circle
			(at -3.4671 1.27)
			(size 1.0414 1.0414)
			(drill 1.0414)
			(layers "*.Cu" "*.Mask")
			(clearance 0.381)
			(thermal_gap 0.381)
		)
		(pad "" np_thru_hole circle
			(at 2.8829 -1.27)
			(size 1.0414 1.0414)
			(drill 1.0414)
			(layers "*.Cu" "*.Mask")
			(clearance 0.381)
			(thermal_gap 0.381)
		)
		(pad "" np_thru_hole circle
			(at 2.8829 1.27)
			(size 1.0414 1.0414)
			(drill 1.0414)
			(layers "*.Cu" "*.Mask")
			(clearance 0.381)
			(thermal_gap 0.381)
		)
		(pad "1" smd rect
			(at -0.8255 -0.249936)
			(size 0.3048 0.508)
			(layers "B.Cu" "B.Mask" "B.Paste")
			(net "85_5INCH_IN1_DN")
		)
		(pad "2" smd rect
			(at -0.8255 0.249936)
			(size 0.3048 0.508)
			(layers "B.Cu" "B.Mask" "B.Paste")
			(net "85_5INCH_IN1_DP")
		)
		(pad "3" smd circle
			(at 0 0 270)
			(size 0 0)
			(layers "B.Cu" "B.Mask" "B.Paste")
			(net "GND_P1")
		)
		(zone
			(layers "F.Cu" "B.Cu" "In1.Cu" "In2.Cu" "In3.Cu" "In4.Cu" "In5.Cu" "In6.Cu"
				"In7.Cu" "In8.Cu" "In9.Cu" "In10.Cu"
			)
			(hatch none 0.5)
			(connect_pads
				(clearance 0)
			)
			(min_thickness 0.25)
			(keepout
				(tracks not_allowed)
				(vias allowed)
				(pads allowed)
				(copperpour not_allowed)
				(footprints allowed)
			)
			(placement
				(enabled no)
				(sheetname "")
			)
			(fill
				(thermal_gap 0.5)
				(thermal_bridge_width 0.5)
				(island_removal_mode 0)
			)
			(polygon
				(pts
					(arc
						(start 95.583756 50.492914)
						(mid 93.729556 50.492914)
						(end 95.583756 50.492914)
					)
				)
			)
		)
		(zone
			(layers "F.Cu" "B.Cu" "In1.Cu" "In2.Cu" "In3.Cu" "In4.Cu" "In5.Cu" "In6.Cu"
				"In7.Cu" "In8.Cu" "In9.Cu" "In10.Cu"
			)
			(hatch none 0.5)
			(connect_pads
				(clearance 0)
			)
			(min_thickness 0.25)
			(keepout
				(tracks not_allowed)
				(vias allowed)
				(pads allowed)
				(copperpour not_allowed)
				(footprints allowed)
			)
			(placement
				(enabled no)
				(sheetname "")
			)
			(fill
				(thermal_gap 0.5)
				(thermal_bridge_width 0.5)
				(island_removal_mode 0)
			)
			(polygon
				(pts
					(arc
						(start 95.583756 56.842914)
						(mid 93.729556 56.842914)
						(end 95.583756 56.842914)
					)
				)
			)
		)
		(zone
			(layers "F.Cu" "B.Cu" "In1.Cu" "In2.Cu" "In3.Cu" "In4.Cu" "In5.Cu" "In6.Cu"
				"In7.Cu" "In8.Cu" "In9.Cu" "In10.Cu"
			)
			(hatch none 0.5)
			(connect_pads
				(clearance 0)
			)
			(min_thickness 0.25)
			(keepout
				(tracks not_allowed)
				(vias allowed)
				(pads allowed)
				(copperpour not_allowed)
				(footprints allowed)
			)
			(placement
				(enabled no)
				(sheetname "")
			)
			(fill
				(thermal_gap 0.5)
				(thermal_bridge_width 0.5)
				(island_removal_mode 0)
			)
			(polygon
				(pts
					(arc
						(start 98.123756 50.492914)
						(mid 96.269556 50.492914)
						(end 98.123756 50.492914)
					)
				)
			)
		)
		(zone
			(layers "F.Cu" "B.Cu" "In1.Cu" "In2.Cu" "In3.Cu" "In4.Cu" "In5.Cu" "In6.Cu"
				"In7.Cu" "In8.Cu" "In9.Cu" "In10.Cu"
			)
			(hatch none 0.5)
			(connect_pads
				(clearance 0)
			)
			(min_thickness 0.25)
			(keepout
				(tracks not_allowed)
				(vias allowed)
				(pads allowed)
				(copperpour not_allowed)
				(footprints allowed)
			)
			(placement
				(enabled no)
				(sheetname "")
			)
			(fill
				(thermal_gap 0.5)
				(thermal_bridge_width 0.5)
				(island_removal_mode 0)
			)
			(polygon
				(pts
					(arc
						(start 98.123756 56.842914)
						(mid 96.269556 56.842914)
						(end 98.123756 56.842914)
					)
				)
			)
		)
		(zone
			(layer "B.Cu")
			(hatch none 0.5)
			(connect_pads
				(clearance 0)
			)
			(min_thickness 0.25)
			(keepout
				(tracks not_allowed)
				(vias allowed)
				(pads allowed)
				(copperpour not_allowed)
				(footprints allowed)
			)
			(placement
				(enabled no)
				(sheetname "")
			)
			(fill
				(thermal_gap 0.5)
				(thermal_bridge_width 0.5)
				(island_removal_mode 0)
			)
			(polygon
				(pts
					(xy 95.378016 54.493414) (xy 95.47352 54.493414) (xy 95.47352 53.896514) (xy 95.87992 53.896514)
					(xy 95.87992 54.493414) (xy 95.973392 54.493414) (xy 95.973392 53.896514) (xy 96.379792 53.896514)
					(xy 96.379792 54.493414) (xy 96.475296 54.493414) (xy 96.475296 53.794914) (xy 95.378016 53.794914)
				)
			)
		)
	)
)
